(kicad_pcb
	(version 20260206)
	(generator "pcbnew")
	(generator_version "10.0")
	(general
		(thickness 1.6)
		(legacy_teardrops no)
	)
	(paper "A4")
	(title_block
		(title "04192023_DAF0TMB3IC0_F0TG_MB_C_brd_V02_OCP.brd")
		(comment 1 "Grand Teton / footprints 5160-5166 of 8354")
	)
	(layers
		(0 "F.Cu" signal "TOP")
		(4 "In1.Cu" signal "GND")
		(6 "In2.Cu" signal "IN1")
		(8 "In3.Cu" signal "GND1")
		(10 "In4.Cu" signal "IN2")
		(12 "In5.Cu" signal "GND2")
		(14 "In6.Cu" signal "IN3")
		(16 "In7.Cu" signal "GND3")
		(18 "In8.Cu" signal "VCC")
		(20 "In9.Cu" signal "VCC1")
		(22 "In10.Cu" signal "GND4")
		(24 "In11.Cu" signal "IN4")
		(26 "In12.Cu" signal "GND5")
		(28 "In13.Cu" signal "IN5")
		(30 "In14.Cu" signal "GND6")
		(32 "In15.Cu" signal "IN6")
		(34 "In16.Cu" signal "GND7")
		(2 "B.Cu" signal "BOTTOM")
		(9 "F.Adhes" user "F.Adhesive")
		(11 "B.Adhes" user "B.Adhesive")
		(13 "F.Paste" user "Package Geometry/Pastemask Top")
		(15 "B.Paste" user "Package Geometry/Pastemask Bottom")
		(5 "F.SilkS" user "Ref Des/Silkscreen Top")
		(7 "B.SilkS" user "Ref Des/Silkscreen Bottom")
		(1 "F.Mask" user "Board Geometry/Soldermask Top")
		(3 "B.Mask" user "Board Geometry/Soldermask Bottom")
		(17 "Dwgs.User" user "User.Drawings")
		(19 "Cmts.User" user "User.Comments")
		(21 "Eco1.User" user "User.Eco1")
		(23 "Eco2.User" user "User.Eco2")
		(25 "Edge.Cuts" user "Board Geometry/Outline")
		(27 "Margin" user)
		(31 "F.CrtYd" user "Package Geometry/Place Bound Top")
		(29 "B.CrtYd" user "Package Geometry/Place Bound Bottom")
		(35 "F.Fab" user "Ref Des/Assembly Top")
		(33 "B.Fab" user "Ref Des/Assembly Bottom")
	)
	(footprint ""
		(layer "B.Cu")
		(at 329.068176 -395.127988 -90)
		(property "Reference" "C506"
			(at 0 0 90)
			(layer "B.SilkS")
			(hide yes)
			(effects
				(font
					(size 1.27 1.27)
				)
				(justify mirror)
			)
		)
		(property "Value" ""
			(at 0 0 90)
			(layer "B.Fab")
			(effects
				(font
					(size 1.27 1.27)
				)
				(justify mirror)
			)
		)
		(duplicate_pad_numbers_are_jumpers no)
		(fp_line
			(start -0.7874 0.4064)
			(end 0.7874 0.4064)
			(stroke
				(width 0.1524)
				(type default)
			)
			(layer "B.SilkS")
		)
		(fp_line
			(start 0.7874 0.4064)
			(end 0.7874 -0.4064)
			(stroke
				(width 0.1524)
				(type default)
			)
			(layer "B.SilkS")
		)
		(fp_line
			(start -0.7874 -0.4064)
			(end -0.7874 0.4064)
			(stroke
				(width 0.1524)
				(type default)
			)
			(layer "B.SilkS")
		)
		(fp_line
			(start 0.7874 -0.4064)
			(end -0.7874 -0.4064)
			(stroke
				(width 0.1524)
				(type default)
			)
			(layer "B.SilkS")
		)
		(fp_line
			(start -0.67945 0.3048)
			(end -0.120396 0.3048)
			(stroke
				(width 0.1)
				(type default)
			)
			(layer "B.Fab")
		)
		(fp_line
			(start -0.120396 0.3048)
			(end -0.120396 0.2794)
			(stroke
				(width 0.1)
				(type default)
			)
			(layer "B.Fab")
		)
		(fp_line
			(start 0.12065 0.3048)
			(end 0.67945 0.3048)
			(stroke
				(width 0.1)
				(type default)
			)
			(layer "B.Fab")
		)
		(fp_line
			(start 0.67945 0.3048)
			(end 0.67945 -0.305054)
			(stroke
				(width 0.1)
				(type default)
			)
			(layer "B.Fab")
		)
		(fp_line
			(start -0.120396 0.2794)
			(end 0.12065 0.2794)
			(stroke
				(width 0.1)
				(type default)
			)
			(layer "B.Fab")
		)
		(fp_line
			(start 0.12065 0.2794)
			(end 0.12065 0.3048)
			(stroke
				(width 0.1)
				(type default)
			)
			(layer "B.Fab")
		)
		(fp_line
			(start -0.12065 -0.2794)
			(end -0.12065 -0.3048)
			(stroke
				(width 0.1)
				(type default)
			)
			(layer "B.Fab")
		)
		(fp_line
			(start 0.12065 -0.2794)
			(end -0.12065 -0.2794)
			(stroke
				(width 0.1)
				(type default)
			)
			(layer "B.Fab")
		)
		(fp_line
			(start -0.67945 -0.3048)
			(end -0.67945 0.3048)
			(stroke
				(width 0.1)
				(type default)
			)
			(layer "B.Fab")
		)
		(fp_line
			(start -0.12065 -0.3048)
			(end -0.67945 -0.3048)
			(stroke
				(width 0.1)
				(type default)
			)
			(layer "B.Fab")
		)
		(fp_line
			(start 0.12065 -0.305054)
			(end 0.12065 -0.2794)
			(stroke
				(width 0.1)
				(type default)
			)
			(layer "B.Fab")
		)
		(fp_line
			(start 0.67945 -0.305054)
			(end 0.12065 -0.305054)
			(stroke
				(width 0.1)
				(type default)
			)
			(layer "B.Fab")
		)
		(pad "1" smd circle
			(at 0.40005 0 90)
			(size 0 0)
			(layers "B.Cu" "B.Mask" "B.Paste")
			(net "P1V8_CPU0_RT_1D")
		)
		(pad "2" smd circle
			(at -0.40005 0 90)
			(size 0 0)
			(layers "B.Cu" "B.Mask" "B.Paste")
			(net "GND")
		)
	)
	(footprint ""
		(layer "B.Cu")
		(at 268.892528 -194.893946 180)
		(property "Reference" "R1573"
			(at 0 0 0)
			(layer "B.SilkS")
			(hide yes)
			(effects
				(font
					(size 1.27 1.27)
				)
				(justify mirror)
			)
		)
		(property "Value" ""
			(at 0 0 0)
			(layer "B.Fab")
			(effects
				(font
					(size 1.27 1.27)
				)
				(justify mirror)
			)
		)
		(duplicate_pad_numbers_are_jumpers no)
		(fp_line
			(start 0.7874 0.4064)
			(end 0.7874 -0.4064)
			(stroke
				(width 0.1524)
				(type default)
			)
			(layer "B.SilkS")
		)
		(fp_line
			(start 0.7874 -0.4064)
			(end -0.7874 -0.4064)
			(stroke
				(width 0.1524)
				(type default)
			)
			(layer "B.SilkS")
		)
		(fp_line
			(start -0.7874 0.4064)
			(end 0.7874 0.4064)
			(stroke
				(width 0.1524)
				(type default)
			)
			(layer "B.SilkS")
		)
		(fp_line
			(start -0.7874 -0.4064)
			(end -0.7874 0.4064)
			(stroke
				(width 0.1524)
				(type default)
			)
			(layer "B.SilkS")
		)
		(fp_line
			(start 0.67945 0.3048)
			(end 0.67945 -0.305054)
			(stroke
				(width 0.1)
				(type default)
			)
			(layer "B.Fab")
		)
		(fp_line
			(start 0.67945 -0.305054)
			(end 0.12065 -0.305054)
			(stroke
				(width 0.1)
				(type default)
			)
			(layer "B.Fab")
		)
		(fp_line
			(start 0.12065 0.3048)
			(end 0.67945 0.3048)
			(stroke
				(width 0.1)
				(type default)
			)
			(layer "B.Fab")
		)
		(fp_line
			(start 0.12065 0.2794)
			(end 0.12065 0.3048)
			(stroke
				(width 0.1)
				(type default)
			)
			(layer "B.Fab")
		)
		(fp_line
			(start 0.12065 -0.2794)
			(end -0.12065 -0.2794)
			(stroke
				(width 0.1)
				(type default)
			)
			(layer "B.Fab")
		)
		(fp_line
			(start 0.12065 -0.305054)
			(end 0.12065 -0.2794)
			(stroke
				(width 0.1)
				(type default)
			)
			(layer "B.Fab")
		)
		(fp_line
			(start -0.120396 0.3048)
			(end -0.120396 0.2794)
			(stroke
				(width 0.1)
				(type default)
			)
			(layer "B.Fab")
		)
		(fp_line
			(start -0.120396 0.2794)
			(end 0.12065 0.2794)
			(stroke
				(width 0.1)
				(type default)
			)
			(layer "B.Fab")
		)
		(fp_line
			(start -0.12065 -0.2794)
			(end -0.12065 -0.3048)
			(stroke
				(width 0.1)
				(type default)
			)
			(layer "B.Fab")
		)
		(fp_line
			(start -0.12065 -0.3048)
			(end -0.67945 -0.3048)
			(stroke
				(width 0.1)
				(type default)
			)
			(layer "B.Fab")
		)
		(fp_line
			(start -0.67945 0.3048)
			(end -0.120396 0.3048)
			(stroke
				(width 0.1)
				(type default)
			)
			(layer "B.Fab")
		)
		(fp_line
			(start -0.67945 -0.3048)
			(end -0.67945 0.3048)
			(stroke
				(width 0.1)
				(type default)
			)
			(layer "B.Fab")
		)
		(pad "1" smd circle
			(at 0.40005 0)
			(size 0 0)
			(layers "B.Cu" "B.Mask" "B.Paste")
			(net "I3C_SPD_DDRAF_CPU0_SCL")
		)
		(pad "2" smd circle
			(at -0.40005 0)
			(size 0 0)
			(layers "B.Cu" "B.Mask" "B.Paste")
			(net "I3C_SPD_DDRF_CPU0_SCL")
		)
	)
	(footprint ""
		(layer "B.Cu")
		(at 393.745466 -395.466062 -90)
		(property "Reference" "C990"
			(at 0 0 90)
			(layer "B.SilkS")
			(hide yes)
			(effects
				(font
					(size 1.27 1.27)
				)
				(justify mirror)
			)
		)
		(property "Value" ""
			(at 0 0 90)
			(layer "B.Fab")
			(effects
				(font
					(size 1.27 1.27)
				)
				(justify mirror)
			)
		)
		(duplicate_pad_numbers_are_jumpers no)
		(fp_line
			(start -1.524 0.762)
			(end 1.524 0.762)
			(stroke
				(width 0.1524)
				(type default)
			)
			(layer "B.SilkS")
		)
		(fp_line
			(start 1.524 0.762)
			(end 1.524 -0.762)
			(stroke
				(width 0.1524)
				(type default)
			)
			(layer "B.SilkS")
		)
		(fp_line
			(start -1.524 -0.762)
			(end -1.524 0.762)
			(stroke
				(width 0.1524)
				(type default)
			)
			(layer "B.SilkS")
		)
		(fp_line
			(start 1.524 -0.762)
			(end -1.524 -0.762)
			(stroke
				(width 0.1524)
				(type default)
			)
			(layer "B.SilkS")
		)
		(fp_line
			(start -1.1049 0.724916)
			(end -1.1049 -0.724916)
			(stroke
				(width 0.1)
				(type default)
			)
			(layer "B.Fab")
		)
		(fp_line
			(start 1.1049 0.724916)
			(end -1.1049 0.724916)
			(stroke
				(width 0.1)
				(type default)
			)
			(layer "B.Fab")
		)
		(fp_line
			(start -1.1049 -0.724916)
			(end 1.1049 -0.724916)
			(stroke
				(width 0.1)
				(type default)
			)
			(layer "B.Fab")
		)
		(fp_line
			(start 1.1049 -0.724916)
			(end 1.1049 0.724916)
			(stroke
				(width 0.1)
				(type default)
			)
			(layer "B.Fab")
		)
		(pad "1" smd rect
			(at 0.889 0 270)
			(size 1.016 1.27)
			(layers "B.Cu" "B.Mask" "B.Paste")
			(net "P1V8_CPU0_RT_1D")
		)
		(pad "2" smd rect
			(at -0.889 0 270)
			(size 1.016 1.27)
			(layers "B.Cu" "B.Mask" "B.Paste")
			(net "GND")
		)
	)
	(footprint ""
		(layer "B.Cu")
		(at 93.4212 -139.192)
		(property "Reference" "R309"
			(at 0 0 0)
			(layer "B.SilkS")
			(hide yes)
			(effects
				(font
					(size 1.27 1.27)
				)
				(justify mirror)
			)
		)
		(property "Value" ""
			(at 0 0 0)
			(layer "B.Fab")
			(effects
				(font
					(size 1.27 1.27)
				)
				(justify mirror)
			)
		)
		(duplicate_pad_numbers_are_jumpers no)
		(fp_line
			(start -0.7874 -0.4064)
			(end -0.7874 0.4064)
			(stroke
				(width 0.1524)
				(type default)
			)
			(layer "B.SilkS")
		)
		(fp_line
			(start -0.7874 0.4064)
			(end 0.7874 0.4064)
			(stroke
				(width 0.1524)
				(type default)
			)
			(layer "B.SilkS")
		)
		(fp_line
			(start 0.7874 -0.4064)
			(end -0.7874 -0.4064)
			(stroke
				(width 0.1524)
				(type default)
			)
			(layer "B.SilkS")
		)
		(fp_line
			(start 0.7874 0.4064)
			(end 0.7874 -0.4064)
			(stroke
				(width 0.1524)
				(type default)
			)
			(layer "B.SilkS")
		)
		(fp_line
			(start -0.67945 -0.3048)
			(end -0.67945 0.3048)
			(stroke
				(width 0.1)
				(type default)
			)
			(layer "B.Fab")
		)
		(fp_line
			(start -0.67945 0.3048)
			(end -0.120396 0.3048)
			(stroke
				(width 0.1)
				(type default)
			)
			(layer "B.Fab")
		)
		(fp_line
			(start -0.12065 -0.3048)
			(end -0.67945 -0.3048)
			(stroke
				(width 0.1)
				(type default)
			)
			(layer "B.Fab")
		)
		(fp_line
			(start -0.12065 -0.2794)
			(end -0.12065 -0.3048)
			(stroke
				(width 0.1)
				(type default)
			)
			(layer "B.Fab")
		)
		(fp_line
			(start -0.120396 0.2794)
			(end 0.12065 0.2794)
			(stroke
				(width 0.1)
				(type default)
			)
			(layer "B.Fab")
		)
		(fp_line
			(start -0.120396 0.3048)
			(end -0.120396 0.2794)
			(stroke
				(width 0.1)
				(type default)
			)
			(layer "B.Fab")
		)
		(fp_line
			(start 0.12065 -0.305054)
			(end 0.12065 -0.2794)
			(stroke
				(width 0.1)
				(type default)
			)
			(layer "B.Fab")
		)
		(fp_line
			(start 0.12065 -0.2794)
			(end -0.12065 -0.2794)
			(stroke
				(width 0.1)
				(type default)
			)
			(layer "B.Fab")
		)
		(fp_line
			(start 0.12065 0.2794)
			(end 0.12065 0.3048)
			(stroke
				(width 0.1)
				(type default)
			)
			(layer "B.Fab")
		)
		(fp_line
			(start 0.12065 0.3048)
			(end 0.67945 0.3048)
			(stroke
				(width 0.1)
				(type default)
			)
			(layer "B.Fab")
		)
		(fp_line
			(start 0.67945 -0.305054)
			(end 0.12065 -0.305054)
			(stroke
				(width 0.1)
				(type default)
			)
			(layer "B.Fab")
		)
		(fp_line
			(start 0.67945 0.3048)
			(end 0.67945 -0.305054)
			(stroke
				(width 0.1)
				(type default)
			)
			(layer "B.Fab")
		)
		(pad "1" smd circle
			(at 0.40005 0 180)
			(size 0 0)
			(layers "B.Cu" "B.Mask" "B.Paste")
			(net "SMB_VR_3V3AUX_SDA")
		)
		(pad "2" smd circle
			(at -0.40005 0 180)
			(size 0 0)
			(layers "B.Cu" "B.Mask" "B.Paste")
			(net "SMB_VR_3V3STBY_SDA")
		)
	)
	(footprint ""
		(layer "B.Cu")
		(at 450.534278 -8.3566 90)
		(property "Reference" "R33"
			(at 0 0 90)
			(layer "B.SilkS")
			(hide yes)
			(effects
				(font
					(size 1.27 1.27)
				)
				(justify mirror)
			)
		)
		(property "Value" ""
			(at 0 0 90)
			(layer "B.Fab")
			(effects
				(font
					(size 1.27 1.27)
				)
				(justify mirror)
			)
		)
		(duplicate_pad_numbers_are_jumpers no)
		(fp_line
			(start 0.7874 -0.4064)
			(end -0.7874 -0.4064)
			(stroke
				(width 0.1524)
				(type default)
			)
			(layer "B.SilkS")
		)
		(fp_line
			(start -0.7874 -0.4064)
			(end -0.7874 0.4064)
			(stroke
				(width 0.1524)
				(type default)
			)
			(layer "B.SilkS")
		)
		(fp_line
			(start 0.7874 0.4064)
			(end 0.7874 -0.4064)
			(stroke
				(width 0.1524)
				(type default)
			)
			(layer "B.SilkS")
		)
		(fp_line
			(start -0.7874 0.4064)
			(end 0.7874 0.4064)
			(stroke
				(width 0.1524)
				(type default)
			)
			(layer "B.SilkS")
		)
		(fp_line
			(start 0.67945 -0.305054)
			(end 0.12065 -0.305054)
			(stroke
				(width 0.1)
				(type default)
			)
			(layer "B.Fab")
		)
		(fp_line
			(start 0.12065 -0.305054)
			(end 0.12065 -0.2794)
			(stroke
				(width 0.1)
				(type default)
			)
			(layer "B.Fab")
		)
		(fp_line
			(start -0.12065 -0.3048)
			(end -0.67945 -0.3048)
			(stroke
				(width 0.1)
				(type default)
			)
			(layer "B.Fab")
		)
		(fp_line
			(start -0.67945 -0.3048)
			(end -0.67945 0.3048)
			(stroke
				(width 0.1)
				(type default)
			)
			(layer "B.Fab")
		)
		(fp_line
			(start 0.12065 -0.2794)
			(end -0.12065 -0.2794)
			(stroke
				(width 0.1)
				(type default)
			)
			(layer "B.Fab")
		)
		(fp_line
			(start -0.12065 -0.2794)
			(end -0.12065 -0.3048)
			(stroke
				(width 0.1)
				(type default)
			)
			(layer "B.Fab")
		)
		(fp_line
			(start 0.12065 0.2794)
			(end 0.12065 0.3048)
			(stroke
				(width 0.1)
				(type default)
			)
			(layer "B.Fab")
		)
		(fp_line
			(start -0.120396 0.2794)
			(end 0.12065 0.2794)
			(stroke
				(width 0.1)
				(type default)
			)
			(layer "B.Fab")
		)
		(fp_line
			(start 0.67945 0.3048)
			(end 0.67945 -0.305054)
			(stroke
				(width 0.1)
				(type default)
			)
			(layer "B.Fab")
		)
		(fp_line
			(start 0.12065 0.3048)
			(end 0.67945 0.3048)
			(stroke
				(width 0.1)
				(type default)
			)
			(layer "B.Fab")
		)
		(fp_line
			(start -0.120396 0.3048)
			(end -0.120396 0.2794)
			(stroke
				(width 0.1)
				(type default)
			)
			(layer "B.Fab")
		)
		(fp_line
			(start -0.67945 0.3048)
			(end -0.120396 0.3048)
			(stroke
				(width 0.1)
				(type default)
			)
			(layer "B.Fab")
		)
		(pad "1" smd circle
			(at 0.40005 0 270)
			(size 0 0)
			(layers "B.Cu" "B.Mask" "B.Paste")
			(net "P3V3_OCP_SFF")
		)
		(pad "2" smd circle
			(at -0.40005 0 270)
			(size 0 0)
			(layers "B.Cu" "B.Mask" "B.Paste")
			(net "OCP_SFF_ID1")
		)
	)
	(footprint ""
		(layer "B.Cu")
		(at 344.668856 -161.263076 -90)
		(property "Reference" "PC159_6"
			(at 0 0 90)
			(layer "B.SilkS")
			(hide yes)
			(effects
				(font
					(size 1.27 1.27)
				)
				(justify mirror)
			)
		)
		(property "Value" ""
			(at 0 0 90)
			(layer "B.Fab")
			(effects
				(font
					(size 1.27 1.27)
				)
				(justify mirror)
			)
		)
		(duplicate_pad_numbers_are_jumpers no)
		(fp_line
			(start -1.524 0.762)
			(end 1.524 0.762)
			(stroke
				(width 0.1524)
				(type default)
			)
			(layer "B.SilkS")
		)
		(fp_line
			(start 1.524 0.762)
			(end 1.524 -0.762)
			(stroke
				(width 0.1524)
				(type default)
			)
			(layer "B.SilkS")
		)
		(fp_line
			(start -1.524 -0.762)
			(end -1.524 0.762)
			(stroke
				(width 0.1524)
				(type default)
			)
			(layer "B.SilkS")
		)
		(fp_line
			(start 1.524 -0.762)
			(end -1.524 -0.762)
			(stroke
				(width 0.1524)
				(type default)
			)
			(layer "B.SilkS")
		)
		(fp_line
			(start -1.1049 0.724916)
			(end -1.1049 -0.724916)
			(stroke
				(width 0.1)
				(type default)
			)
			(layer "B.Fab")
		)
		(fp_line
			(start 1.1049 0.724916)
			(end -1.1049 0.724916)
			(stroke
				(width 0.1)
				(type default)
			)
			(layer "B.Fab")
		)
		(fp_line
			(start -1.1049 -0.724916)
			(end 1.1049 -0.724916)
			(stroke
				(width 0.1)
				(type default)
			)
			(layer "B.Fab")
		)
		(fp_line
			(start 1.1049 -0.724916)
			(end 1.1049 0.724916)
			(stroke
				(width 0.1)
				(type default)
			)
			(layer "B.Fab")
		)
		(pad "1" smd rect
			(at 0.889 0 270)
			(size 1.016 1.27)
			(layers "B.Cu" "B.Mask" "B.Paste")
			(net "SW_P12V_AUX_PVDDCR_CPU0_P0_FLT")
		)
		(pad "2" smd rect
			(at -0.889 0 270)
			(size 1.016 1.27)
			(layers "B.Cu" "B.Mask" "B.Paste")
			(net "GND")
		)
	)
	(footprint ""
		(layer "B.Cu")
		(at 106.212386 -253.432564)
		(property "Reference" "C2436"
			(at 0 0 0)
			(layer "B.SilkS")
			(hide yes)
			(effects
				(font
					(size 1.27 1.27)
				)
				(justify mirror)
			)
		)
		(property "Value" ""
			(at 0 0 0)
			(layer "B.Fab")
			(effects
				(font
					(size 1.27 1.27)
				)
				(justify mirror)
			)
		)
		(duplicate_pad_numbers_are_jumpers no)
		(fp_line
			(start -0.7874 -0.4064)
			(end -0.7874 0.4064)
			(stroke
				(width 0.1524)
				(type default)
			)
			(layer "B.SilkS")
		)
		(fp_line
			(start -0.7874 0.4064)
			(end 0.7874 0.4064)
			(stroke
				(width 0.1524)
				(type default)
			)
			(layer "B.SilkS")
		)
		(fp_line
			(start 0.7874 -0.4064)
			(end -0.7874 -0.4064)
			(stroke
				(width 0.1524)
				(type default)
			)
			(layer "B.SilkS")
		)
		(fp_line
			(start 0.7874 0.4064)
			(end 0.7874 -0.4064)
			(stroke
				(width 0.1524)
				(type default)
			)
			(layer "B.SilkS")
		)
		(fp_line
			(start -0.67945 -0.3048)
			(end -0.67945 0.3048)
			(stroke
				(width 0.1)
				(type default)
			)
			(layer "B.Fab")
		)
		(fp_line
			(start -0.67945 0.3048)
			(end -0.120396 0.3048)
			(stroke
				(width 0.1)
				(type default)
			)
			(layer "B.Fab")
		)
		(fp_line
			(start -0.12065 -0.3048)
			(end -0.67945 -0.3048)
			(stroke
				(width 0.1)
				(type default)
			)
			(layer "B.Fab")
		)
		(fp_line
			(start -0.12065 -0.2794)
			(end -0.12065 -0.3048)
			(stroke
				(width 0.1)
				(type default)
			)
			(layer "B.Fab")
		)
		(fp_line
			(start -0.120396 0.2794)
			(end 0.12065 0.2794)
			(stroke
				(width 0.1)
				(type default)
			)
			(layer "B.Fab")
		)
		(fp_line
			(start -0.120396 0.3048)
			(end -0.120396 0.2794)
			(stroke
				(width 0.1)
				(type default)
			)
			(layer "B.Fab")
		)
		(fp_line
			(start 0.12065 -0.305054)
			(end 0.12065 -0.2794)
			(stroke
				(width 0.1)
				(type default)
			)
			(layer "B.Fab")
		)
		(fp_line
			(start 0.12065 -0.2794)
			(end -0.12065 -0.2794)
			(stroke
				(width 0.1)
				(type default)
			)
			(layer "B.Fab")
		)
		(fp_line
			(start 0.12065 0.2794)
			(end 0.12065 0.3048)
			(stroke
				(width 0.1)
				(type default)
			)
			(layer "B.Fab")
		)
		(fp_line
			(start 0.12065 0.3048)
			(end 0.67945 0.3048)
			(stroke
				(width 0.1)
				(type default)
			)
			(layer "B.Fab")
		)
		(fp_line
			(start 0.67945 -0.305054)
			(end 0.12065 -0.305054)
			(stroke
				(width 0.1)
				(type default)
			)
			(layer "B.Fab")
		)
		(fp_line
			(start 0.67945 0.3048)
			(end 0.67945 -0.305054)
			(stroke
				(width 0.1)
				(type default)
			)
			(layer "B.Fab")
		)
		(pad "1" smd circle
			(at 0.40005 0 180)
			(size 0 0)
			(layers "B.Cu" "B.Mask" "B.Paste")
			(net "PVDDCR_SOC_P1")
		)
		(pad "2" smd circle
			(at -0.40005 0 180)
			(size 0 0)
			(layers "B.Cu" "B.Mask" "B.Paste")
			(net "GND")
		)
	)
)
